(kicad_pcb
	(version 20260206)
	(generator "pcbnew")
	(generator_version "10.0")
	(general
		(thickness 1.6)
		(legacy_teardrops no)
	)
	(paper "A4")
	(title_block
		(title "peb — Lightning_PEB_BRD.brd")
		(comment 1 "Lightning (Wiwynn / Facebook NVMe JBOF) / footprints 431-431 of 2563")
	)
	(layers
		(0 "F.Cu" signal "TOP")
		(4 "In1.Cu" signal "L2GND")
		(6 "In2.Cu" signal "L3")
		(8 "In3.Cu" signal "L4VCC")
		(10 "In4.Cu" signal "L5VCC")
		(12 "In5.Cu" signal "L6")
		(14 "In6.Cu" signal "L7GND")
		(2 "B.Cu" signal "BOTTOM")
		(9 "F.Adhes" user "F.Adhesive")
		(11 "B.Adhes" user "B.Adhesive")
		(13 "F.Paste" user "Package Geometry/Pastemask Top")
		(15 "B.Paste" user "Package Geometry/Pastemask Bottom")
		(5 "F.SilkS" user "Ref Des/Silkscreen Top")
		(7 "B.SilkS" user "Ref Des/Silkscreen Bottom")
		(1 "F.Mask" user "Board Geometry/Soldermask Top")
		(3 "B.Mask" user "Board Geometry/Soldermask Bottom")
		(17 "Dwgs.User" user "User.Drawings")
		(19 "Cmts.User" user "User.Comments")
		(21 "Eco1.User" user "User.Eco1")
		(23 "Eco2.User" user "User.Eco2")
		(25 "Edge.Cuts" user "Board Geometry/Outline")
		(27 "Margin" user)
		(31 "F.CrtYd" user "Package Geometry/Place Bound Top")
		(29 "B.CrtYd" user "Package Geometry/Place Bound Bottom")
		(35 "F.Fab" user "Ref Des/Assembly Top")
		(33 "B.Fab" user "Ref Des/Assembly Bottom")
	)
	(footprint ""
		(layer "F.Cu")
		(at 53.781452 -108.11383 -90)
		(property "Reference" "R65"
			(at 0 0 270)
			(layer "F.SilkS")
			(hide yes)
			(effects
				(font
					(size 1.27 1.27)
				)
			)
		)
		(property "Value" "0R2J-2-GP"
			(at 0.064008 -3.993896 270)
			(unlocked yes)
			(layer "F.Fab")
			(hide yes)
			(effects
				(font
					(size 1.016 1.016)
					(thickness 0.1524)
				)
			)
		)
		(property "Device Type" "R402H16"
			(at 0.064008 -5.517896 270)
			(unlocked yes)
			(layer "F.Fab")
			(hide yes)
			(effects
				(font
					(size 1.016 1.016)
					(thickness 0.1524)
				)
			)
		)
		(duplicate_pad_numbers_are_jumpers no)
		(fp_line
			(start -0.508 -0.9398)
			(end -0.508 0.9398)
			(stroke
				(width 0.1524)
				(type default)
			)
			(layer "F.SilkS")
		)
		(fp_line
			(start 0.508 -0.9398)
			(end -0.508 -0.9398)
			(stroke
				(width 0.1524)
				(type default)
			)
			(layer "F.SilkS")
		)
		(fp_rect
			(start -0.508 0.9398)
			(end 0.508 -0.9398)
			(stroke
				(width 0)
				(type default)
			)
			(fill no)
			(layer "F.CrtYd")
		)
		(fp_rect
			(start -0.508 0.9398)
			(end 0.508 -0.9398)
			(stroke
				(width 0)
				(type default)
			)
			(fill no)
			(layer "F.Fab")
		)
		(pad "1" smd custom
			(at 0 -0.4445 270)
			(size 0.1397 0.1397)
			(layers "F.Cu" "F.Mask" "F.Paste")
			(net "BMC_I2C13_MINI7_SCL_S")
			(options
				(clearance outline)
				(anchor circle)
			)
			(primitives
				(gr_poly
					(pts
						(arc
							(start -0.1778 -0.2794)
							(mid -0.249642 -0.249642)
							(end -0.2794 -0.1778)
						)
						(arc
							(start -0.2794 0.1778)
							(mid -0.249642 0.249642)
							(end -0.1778 0.2794)
						)
						(arc
							(start 0.1778 0.2794)
							(mid 0.249642 0.249642)
							(end 0.2794 0.1778)
						)
						(arc
							(start 0.2794 -0.1778)
							(mid 0.249642 -0.249642)
							(end 0.1778 -0.2794)
						)
					)
					(width 0)
					(fill yes)
				)
			)
		)
		(pad "2" smd custom
			(at 0 0.4445 270)
			(size 0.1397 0.1397)
			(layers "F.Cu" "F.Mask" "F.Paste")
			(net "BMC_I2C13_MINI7_SCL")
			(options
				(clearance outline)
				(anchor circle)
			)
			(primitives
				(gr_poly
					(pts
						(arc
							(start -0.1778 -0.2794)
							(mid -0.249642 -0.249642)
							(end -0.2794 -0.1778)
						)
						(arc
							(start -0.2794 0.1778)
							(mid -0.249642 0.249642)
							(end -0.1778 0.2794)
						)
						(arc
							(start 0.1778 0.2794)
							(mid 0.249642 0.249642)
							(end 0.2794 0.1778)
						)
						(arc
							(start 0.2794 -0.1778)
							(mid 0.249642 -0.249642)
							(end 0.1778 -0.2794)
						)
					)
					(width 0)
					(fill yes)
				)
			)
		)
	)
)
